# S9S_MB_2U (Grand Teton) — schematic netlist excerpt (pin names and nets, part order shuffled) for the footprints in the layout excerpt that follows; sources: Cadence DE-HDL packaged netlist, KiCad conversion of 03242023_DA0F0TMBIJ0_F0T_Motherboard_J_brd_V01_OCP.brd

R3176  Q_RES  1K 1% CHIP  pkg 0402LF  page 159 : A = SGPIO_OCP_V3_2_CLK ; B = P3V3_OCP_V3_2
PC725_P1_2  Q_CAP  22UF 16V 20% X6S  pkg C0805  page 289 : A = SW_P12V_PVCCFA_EHV_FIVRA_CPU1_L ; B = GND
PC330  Q_CAP  0.1UF 25V 10% X7R  pkg 0402  page 266 : A = PVCCIN_CPU0_VIN_CSNIN ; B = GND

(kicad_pcb
	(version 20260206)
	(generator "pcbnew")
	(generator_version "10.0")
	(general
		(thickness 1.6)
		(legacy_teardrops no)
	)
	(paper "A4")
	(title_block
		(title "03242023_DA0F0TMBIJ0_F0T_Motherboard_J_brd_V01_OCP.brd")
		(comment 1 "Grand Teton / footprints 3150-3152 of 6105")
	)
	(layers
		(0 "F.Cu" signal "TOP")
		(4 "In1.Cu" signal "GND")
		(6 "In2.Cu" signal "IN1")
		(8 "In3.Cu" signal "GND1")
		(10 "In4.Cu" signal "IN2")
		(12 "In5.Cu" signal "GND2")
		(14 "In6.Cu" signal "IN3")
		(16 "In7.Cu" signal "GND3")
		(18 "In8.Cu" signal "VCC")
		(20 "In9.Cu" signal "VCC1")
		(22 "In10.Cu" signal "GND4")
		(24 "In11.Cu" signal "IN4")
		(26 "In12.Cu" signal "GND5")
		(28 "In13.Cu" signal "IN5")
		(30 "In14.Cu" signal "GND6")
		(32 "In15.Cu" signal "IN6")
		(34 "In16.Cu" signal "GND7")
		(2 "B.Cu" signal "BOTTOM")
		(9 "F.Adhes" user "F.Adhesive")
		(11 "B.Adhes" user "B.Adhesive")
		(13 "F.Paste" user "Package Geometry/Pastemask Top")
		(15 "B.Paste" user "Package Geometry/Pastemask Bottom")
		(5 "F.SilkS" user "Ref Des/Silkscreen Top")
		(7 "B.SilkS" user "Ref Des/Silkscreen Bottom")
		(1 "F.Mask" user "Board Geometry/Soldermask Top")
		(3 "B.Mask" user "Board Geometry/Soldermask Bottom")
		(17 "Dwgs.User" user "User.Drawings")
		(19 "Cmts.User" user "User.Comments")
		(21 "Eco1.User" user "User.Eco1")
		(23 "Eco2.User" user "User.Eco2")
		(25 "Edge.Cuts" user "Board Geometry/Outline")
		(27 "Margin" user)
		(31 "F.CrtYd" user "Package Geometry/Place Bound Top")
		(29 "B.CrtYd" user "Package Geometry/Place Bound Bottom")
		(35 "F.Fab" user "Ref Des/Assembly Top")
		(33 "B.Fab" user "Ref Des/Assembly Bottom")
	)
	(footprint ""
		(layer "F.Cu")
		(at 164.64788 -120.106948 180)
		(property "Reference" "R3176"
			(at 0 0 180)
			(layer "F.SilkS")
			(hide yes)
			(effects
				(font
					(size 1.27 1.27)
				)
			)
		)
		(property "Value" ""
			(at 0 0 180)
			(layer "F.Fab")
			(effects
				(font
					(size 1.27 1.27)
				)
			)
		)
		(duplicate_pad_numbers_are_jumpers no)
		(fp_line
			(start 0.7874 0.4064)
			(end -0.7874 0.4064)
			(stroke
				(width 0.1524)
				(type default)
			)
			(layer "F.SilkS")
		)
		(fp_line
			(start 0.7874 -0.4064)
			(end 0.7874 0.4064)
			(stroke
				(width 0.1524)
				(type default)
			)
			(layer "F.SilkS")
		)
		(fp_line
			(start -0.7874 0.4064)
			(end -0.7874 -0.4064)
			(stroke
				(width 0.1524)
				(type default)
			)
			(layer "F.SilkS")
		)
		(fp_line
			(start -0.7874 -0.4064)
			(end 0.7874 -0.4064)
			(stroke
				(width 0.1524)
				(type default)
			)
			(layer "F.SilkS")
		)
		(fp_line
			(start 0.67945 0.3048)
			(end 0.120396 0.3048)
			(stroke
				(width 0.1)
				(type default)
			)
			(layer "F.Fab")
		)
		(fp_line
			(start 0.67945 -0.3048)
			(end 0.67945 0.3048)
			(stroke
				(width 0.1)
				(type default)
			)
			(layer "F.Fab")
		)
		(fp_line
			(start 0.12065 -0.2794)
			(end 0.12065 -0.3048)
			(stroke
				(width 0.1)
				(type default)
			)
			(layer "F.Fab")
		)
		(fp_line
			(start 0.12065 -0.3048)
			(end 0.67945 -0.3048)
			(stroke
				(width 0.1)
				(type default)
			)
			(layer "F.Fab")
		)
		(fp_line
			(start 0.120396 0.3048)
			(end 0.120396 0.2794)
			(stroke
				(width 0.1)
				(type default)
			)
			(layer "F.Fab")
		)
		(fp_line
			(start 0.120396 0.2794)
			(end -0.12065 0.2794)
			(stroke
				(width 0.1)
				(type default)
			)
			(layer "F.Fab")
		)
		(fp_line
			(start -0.12065 0.3048)
			(end -0.67945 0.3048)
			(stroke
				(width 0.1)
				(type default)
			)
			(layer "F.Fab")
		)
		(fp_line
			(start -0.12065 0.2794)
			(end -0.12065 0.3048)
			(stroke
				(width 0.1)
				(type default)
			)
			(layer "F.Fab")
		)
		(fp_line
			(start -0.12065 -0.2794)
			(end 0.12065 -0.2794)
			(stroke
				(width 0.1)
				(type default)
			)
			(layer "F.Fab")
		)
		(fp_line
			(start -0.12065 -0.305054)
			(end -0.12065 -0.2794)
			(stroke
				(width 0.1)
				(type default)
			)
			(layer "F.Fab")
		)
		(fp_line
			(start -0.67945 0.3048)
			(end -0.67945 -0.305054)
			(stroke
				(width 0.1)
				(type default)
			)
			(layer "F.Fab")
		)
		(fp_line
			(start -0.67945 -0.305054)
			(end -0.12065 -0.305054)
			(stroke
				(width 0.1)
				(type default)
			)
			(layer "F.Fab")
		)
		(pad "1" smd circle
			(at -0.40005 0 180)
			(size 0 0)
			(layers "F.Cu" "F.Mask" "F.Paste")
			(net "SGPIO_OCP_V3_2_CLK")
		)
		(pad "2" smd circle
			(at 0.40005 0 180)
			(size 0 0)
			(layers "F.Cu" "F.Mask" "F.Paste")
			(net "P3V3_OCP_V3_2")
		)
	)
	(footprint ""
		(layer "F.Cu")
		(at 362.646468 -360.83875)
		(property "Reference" "PC330"
			(at 0 0 0)
			(layer "F.SilkS")
			(hide yes)
			(effects
				(font
					(size 1.27 1.27)
				)
			)
		)
		(property "Value" ""
			(at 0 0 0)
			(layer "F.Fab")
			(effects
				(font
					(size 1.27 1.27)
				)
			)
		)
		(duplicate_pad_numbers_are_jumpers no)
		(fp_line
			(start -0.7874 -0.4064)
			(end 0.7874 -0.4064)
			(stroke
				(width 0.1524)
				(type default)
			)
			(layer "F.SilkS")
		)
		(fp_line
			(start -0.7874 0.4064)
			(end -0.7874 -0.4064)
			(stroke
				(width 0.1524)
				(type default)
			)
			(layer "F.SilkS")
		)
		(fp_line
			(start 0.7874 -0.4064)
			(end 0.7874 0.4064)
			(stroke
				(width 0.1524)
				(type default)
			)
			(layer "F.SilkS")
		)
		(fp_line
			(start 0.7874 0.4064)
			(end -0.7874 0.4064)
			(stroke
				(width 0.1524)
				(type default)
			)
			(layer "F.SilkS")
		)
		(fp_line
			(start -0.67945 -0.305054)
			(end -0.12065 -0.305054)
			(stroke
				(width 0.1)
				(type default)
			)
			(layer "F.Fab")
		)
		(fp_line
			(start -0.67945 0.3048)
			(end -0.67945 -0.305054)
			(stroke
				(width 0.1)
				(type default)
			)
			(layer "F.Fab")
		)
		(fp_line
			(start -0.12065 -0.305054)
			(end -0.12065 -0.2794)
			(stroke
				(width 0.1)
				(type default)
			)
			(layer "F.Fab")
		)
		(fp_line
			(start -0.12065 -0.2794)
			(end 0.12065 -0.2794)
			(stroke
				(width 0.1)
				(type default)
			)
			(layer "F.Fab")
		)
		(fp_line
			(start -0.12065 0.2794)
			(end -0.12065 0.3048)
			(stroke
				(width 0.1)
				(type default)
			)
			(layer "F.Fab")
		)
		(fp_line
			(start -0.12065 0.3048)
			(end -0.67945 0.3048)
			(stroke
				(width 0.1)
				(type default)
			)
			(layer "F.Fab")
		)
		(fp_line
			(start 0.120396 0.2794)
			(end -0.12065 0.2794)
			(stroke
				(width 0.1)
				(type default)
			)
			(layer "F.Fab")
		)
		(fp_line
			(start 0.120396 0.3048)
			(end 0.120396 0.2794)
			(stroke
				(width 0.1)
				(type default)
			)
			(layer "F.Fab")
		)
		(fp_line
			(start 0.12065 -0.3048)
			(end 0.67945 -0.3048)
			(stroke
				(width 0.1)
				(type default)
			)
			(layer "F.Fab")
		)
		(fp_line
			(start 0.12065 -0.2794)
			(end 0.12065 -0.3048)
			(stroke
				(width 0.1)
				(type default)
			)
			(layer "F.Fab")
		)
		(fp_line
			(start 0.67945 -0.3048)
			(end 0.67945 0.3048)
			(stroke
				(width 0.1)
				(type default)
			)
			(layer "F.Fab")
		)
		(fp_line
			(start 0.67945 0.3048)
			(end 0.120396 0.3048)
			(stroke
				(width 0.1)
				(type default)
			)
			(layer "F.Fab")
		)
		(pad "1" smd circle
			(at -0.40005 0)
			(size 0 0)
			(layers "F.Cu" "F.Mask" "F.Paste")
			(net "PVCCIN_CPU0_VIN_CSNIN")
		)
		(pad "2" smd circle
			(at 0.40005 0)
			(size 0 0)
			(layers "F.Cu" "F.Mask" "F.Paste")
			(net "GND")
		)
	)
	(footprint ""
		(layer "F.Cu")
		(at 56.282844 -358.11841)
		(property "Reference" "PC725_P1_2"
			(at 0 0 0)
			(layer "F.SilkS")
			(hide yes)
			(effects
				(font
					(size 1.27 1.27)
				)
			)
		)
		(property "Value" ""
			(at 0 0 0)
			(layer "F.Fab")
			(effects
				(font
					(size 1.27 1.27)
				)
			)
		)
		(duplicate_pad_numbers_are_jumpers no)
		(fp_line
			(start -1.524 -0.762)
			(end 1.524 -0.762)
			(stroke
				(width 0.1524)
				(type default)
			)
			(layer "F.SilkS")
		)
		(fp_line
			(start -1.524 0.762)
			(end -1.524 -0.762)
			(stroke
				(width 0.1524)
				(type default)
			)
			(layer "F.SilkS")
		)
		(fp_line
			(start 1.524 -0.762)
			(end 1.524 0.762)
			(stroke
				(width 0.1524)
				(type default)
			)
			(layer "F.SilkS")
		)
		(fp_line
			(start 1.524 0.762)
			(end -1.524 0.762)
			(stroke
				(width 0.1524)
				(type default)
			)
			(layer "F.SilkS")
		)
		(fp_line
			(start -1.1049 -0.724916)
			(end -1.1049 0.724916)
			(stroke
				(width 0.1)
				(type default)
			)
			(layer "F.Fab")
		)
		(fp_line
			(start -1.1049 0.724916)
			(end 1.1049 0.724916)
			(stroke
				(width 0.1)
				(type default)
			)
			(layer "F.Fab")
		)
		(fp_line
			(start 1.1049 -0.724916)
			(end -1.1049 -0.724916)
			(stroke
				(width 0.1)
				(type default)
			)
			(layer "F.Fab")
		)
		(fp_line
			(start 1.1049 0.724916)
			(end 1.1049 -0.724916)
			(stroke
				(width 0.1)
				(type default)
			)
			(layer "F.Fab")
		)
		(pad "1" smd rect
			(at -0.889 0 180)
			(size 1.016 1.27)
			(layers "F.Cu" "F.Mask" "F.Paste")
			(net "SW_P12V_PVCCFA_EHV_FIVRA_CPU1_L")
		)
		(pad "2" smd rect
			(at 0.889 0 180)
			(size 1.016 1.27)
			(layers "F.Cu" "F.Mask" "F.Paste")
			(net "GND")
		)
	)
)
